(kicad_pcb
	(version 20260206)
	(generator "pcbnew")
	(generator_version "10.0")
	(general
		(thickness 1.6)
		(legacy_teardrops no)
	)
	(paper "A4")
	(title_block
		(title "01162023_DA0F0TEBIF0_F0T_Expander_BD_F_brd_V02_OCP.brd")
		(comment 1 "Grand Teton / footprints 9662-9668 of 9728")
	)
	(layers
		(0 "F.Cu" signal "TOP")
		(4 "In1.Cu" signal "GND")
		(6 "In2.Cu" signal "VCC")
		(8 "In3.Cu" signal "VCC1")
		(10 "In4.Cu" signal "GND1")
		(12 "In5.Cu" signal "IN1")
		(14 "In6.Cu" signal "GND2")
		(16 "In7.Cu" signal "IN2")
		(18 "In8.Cu" signal "GND3")
		(20 "In9.Cu" signal "IN3")
		(22 "In10.Cu" signal "GND4")
		(24 "In11.Cu" signal "IN4")
		(26 "In12.Cu" signal "GND5")
		(28 "In13.Cu" signal "IN5")
		(30 "In14.Cu" signal "GND6")
		(32 "In15.Cu" signal "IN6")
		(34 "In16.Cu" signal "GND7")
		(2 "B.Cu" signal "BOTTOM")
		(9 "F.Adhes" user "F.Adhesive")
		(11 "B.Adhes" user "B.Adhesive")
		(13 "F.Paste" user "Package Geometry/Pastemask Top")
		(15 "B.Paste" user "Package Geometry/Pastemask Bottom")
		(5 "F.SilkS" user "Ref Des/Silkscreen Top")
		(7 "B.SilkS" user "Ref Des/Silkscreen Bottom")
		(1 "F.Mask" user "Board Geometry/Soldermask Top")
		(3 "B.Mask" user "Board Geometry/Soldermask Bottom")
		(17 "Dwgs.User" user "User.Drawings")
		(19 "Cmts.User" user "User.Comments")
		(21 "Eco1.User" user "User.Eco1")
		(23 "Eco2.User" user "User.Eco2")
		(25 "Edge.Cuts" user "Board Geometry/Outline")
		(27 "Margin" user)
		(31 "F.CrtYd" user "Package Geometry/Place Bound Top")
		(29 "B.CrtYd" user "Package Geometry/Place Bound Bottom")
		(35 "F.Fab" user "Ref Des/Assembly Top")
		(33 "B.Fab" user "Ref Des/Assembly Bottom")
	)
	(footprint ""
		(layer "B.Cu")
		(at 379.349 -239.141 -90)
		(property "Reference" "C2565"
			(at 0 0 90)
			(layer "B.SilkS")
			(hide yes)
			(effects
				(font
					(size 1.27 1.27)
				)
				(justify mirror)
			)
		)
		(property "Value" ""
			(at 0 0 90)
			(layer "B.Fab")
			(effects
				(font
					(size 1.27 1.27)
				)
				(justify mirror)
			)
		)
		(duplicate_pad_numbers_are_jumpers no)
		(fp_line
			(start -0.7874 0.4064)
			(end 0.7874 0.4064)
			(stroke
				(width 0.1524)
				(type default)
			)
			(layer "B.SilkS")
		)
		(fp_line
			(start 0.7874 0.4064)
			(end 0.7874 -0.4064)
			(stroke
				(width 0.1524)
				(type default)
			)
			(layer "B.SilkS")
		)
		(fp_line
			(start -0.7874 -0.4064)
			(end -0.7874 0.4064)
			(stroke
				(width 0.1524)
				(type default)
			)
			(layer "B.SilkS")
		)
		(fp_line
			(start 0.7874 -0.4064)
			(end -0.7874 -0.4064)
			(stroke
				(width 0.1524)
				(type default)
			)
			(layer "B.SilkS")
		)
		(fp_line
			(start -0.67945 0.3048)
			(end -0.120396 0.3048)
			(stroke
				(width 0.1)
				(type default)
			)
			(layer "B.Fab")
		)
		(fp_line
			(start -0.120396 0.3048)
			(end -0.120396 0.2794)
			(stroke
				(width 0.1)
				(type default)
			)
			(layer "B.Fab")
		)
		(fp_line
			(start 0.12065 0.3048)
			(end 0.67945 0.3048)
			(stroke
				(width 0.1)
				(type default)
			)
			(layer "B.Fab")
		)
		(fp_line
			(start 0.67945 0.3048)
			(end 0.67945 -0.305054)
			(stroke
				(width 0.1)
				(type default)
			)
			(layer "B.Fab")
		)
		(fp_line
			(start -0.120396 0.2794)
			(end 0.12065 0.2794)
			(stroke
				(width 0.1)
				(type default)
			)
			(layer "B.Fab")
		)
		(fp_line
			(start 0.12065 0.2794)
			(end 0.12065 0.3048)
			(stroke
				(width 0.1)
				(type default)
			)
			(layer "B.Fab")
		)
		(fp_line
			(start -0.12065 -0.2794)
			(end -0.12065 -0.3048)
			(stroke
				(width 0.1)
				(type default)
			)
			(layer "B.Fab")
		)
		(fp_line
			(start 0.12065 -0.2794)
			(end -0.12065 -0.2794)
			(stroke
				(width 0.1)
				(type default)
			)
			(layer "B.Fab")
		)
		(fp_line
			(start -0.67945 -0.3048)
			(end -0.67945 0.3048)
			(stroke
				(width 0.1)
				(type default)
			)
			(layer "B.Fab")
		)
		(fp_line
			(start -0.12065 -0.3048)
			(end -0.67945 -0.3048)
			(stroke
				(width 0.1)
				(type default)
			)
			(layer "B.Fab")
		)
		(fp_line
			(start 0.12065 -0.305054)
			(end 0.12065 -0.2794)
			(stroke
				(width 0.1)
				(type default)
			)
			(layer "B.Fab")
		)
		(fp_line
			(start 0.67945 -0.305054)
			(end 0.12065 -0.305054)
			(stroke
				(width 0.1)
				(type default)
			)
			(layer "B.Fab")
		)
		(pad "1" smd circle
			(at 0.40005 0 90)
			(size 0 0)
			(layers "B.Cu" "B.Mask" "B.Paste")
			(net "P3V3_AUX")
		)
		(pad "2" smd circle
			(at -0.40005 0 90)
			(size 0 0)
			(layers "B.Cu" "B.Mask" "B.Paste")
			(net "GND")
		)
	)
	(footprint ""
		(layer "B.Cu")
		(at 225.370644 -231.225598 -90)
		(property "Reference" "R4556"
			(at 0 0 90)
			(layer "B.SilkS")
			(hide yes)
			(effects
				(font
					(size 1.27 1.27)
				)
				(justify mirror)
			)
		)
		(property "Value" ""
			(at 0 0 90)
			(layer "B.Fab")
			(effects
				(font
					(size 1.27 1.27)
				)
				(justify mirror)
			)
		)
		(duplicate_pad_numbers_are_jumpers no)
		(fp_line
			(start -0.7874 0.4064)
			(end 0.7874 0.4064)
			(stroke
				(width 0.1524)
				(type default)
			)
			(layer "B.SilkS")
		)
		(fp_line
			(start 0.7874 0.4064)
			(end 0.7874 -0.4064)
			(stroke
				(width 0.1524)
				(type default)
			)
			(layer "B.SilkS")
		)
		(fp_line
			(start -0.7874 -0.4064)
			(end -0.7874 0.4064)
			(stroke
				(width 0.1524)
				(type default)
			)
			(layer "B.SilkS")
		)
		(fp_line
			(start 0.7874 -0.4064)
			(end -0.7874 -0.4064)
			(stroke
				(width 0.1524)
				(type default)
			)
			(layer "B.SilkS")
		)
		(fp_line
			(start -0.67945 0.3048)
			(end -0.120396 0.3048)
			(stroke
				(width 0.1)
				(type default)
			)
			(layer "B.Fab")
		)
		(fp_line
			(start -0.120396 0.3048)
			(end -0.120396 0.2794)
			(stroke
				(width 0.1)
				(type default)
			)
			(layer "B.Fab")
		)
		(fp_line
			(start 0.12065 0.3048)
			(end 0.67945 0.3048)
			(stroke
				(width 0.1)
				(type default)
			)
			(layer "B.Fab")
		)
		(fp_line
			(start 0.67945 0.3048)
			(end 0.67945 -0.305054)
			(stroke
				(width 0.1)
				(type default)
			)
			(layer "B.Fab")
		)
		(fp_line
			(start -0.120396 0.2794)
			(end 0.12065 0.2794)
			(stroke
				(width 0.1)
				(type default)
			)
			(layer "B.Fab")
		)
		(fp_line
			(start 0.12065 0.2794)
			(end 0.12065 0.3048)
			(stroke
				(width 0.1)
				(type default)
			)
			(layer "B.Fab")
		)
		(fp_line
			(start -0.12065 -0.2794)
			(end -0.12065 -0.3048)
			(stroke
				(width 0.1)
				(type default)
			)
			(layer "B.Fab")
		)
		(fp_line
			(start 0.12065 -0.2794)
			(end -0.12065 -0.2794)
			(stroke
				(width 0.1)
				(type default)
			)
			(layer "B.Fab")
		)
		(fp_line
			(start -0.67945 -0.3048)
			(end -0.67945 0.3048)
			(stroke
				(width 0.1)
				(type default)
			)
			(layer "B.Fab")
		)
		(fp_line
			(start -0.12065 -0.3048)
			(end -0.67945 -0.3048)
			(stroke
				(width 0.1)
				(type default)
			)
			(layer "B.Fab")
		)
		(fp_line
			(start 0.12065 -0.305054)
			(end 0.12065 -0.2794)
			(stroke
				(width 0.1)
				(type default)
			)
			(layer "B.Fab")
		)
		(fp_line
			(start 0.67945 -0.305054)
			(end 0.12065 -0.305054)
			(stroke
				(width 0.1)
				(type default)
			)
			(layer "B.Fab")
		)
		(pad "1" smd circle
			(at 0.40005 0 90)
			(size 0 0)
			(layers "B.Cu" "B.Mask" "B.Paste")
			(net "BIC_FORCE_THROTTLE_N")
		)
		(pad "2" smd circle
			(at -0.40005 0 90)
			(size 0 0)
			(layers "B.Cu" "B.Mask" "B.Paste")
			(net "BIC_FORCE_THROTTLE_R_N")
		)
	)
	(footprint ""
		(layer "B.Cu")
		(at 212.09 -206.121 -90)
		(property "Reference" "R1513"
			(at 0 0 90)
			(layer "B.SilkS")
			(hide yes)
			(effects
				(font
					(size 1.27 1.27)
				)
				(justify mirror)
			)
		)
		(property "Value" ""
			(at 0 0 90)
			(layer "B.Fab")
			(effects
				(font
					(size 1.27 1.27)
				)
				(justify mirror)
			)
		)
		(duplicate_pad_numbers_are_jumpers no)
		(fp_line
			(start -0.7874 0.4064)
			(end 0.7874 0.4064)
			(stroke
				(width 0.1524)
				(type default)
			)
			(layer "B.SilkS")
		)
		(fp_line
			(start 0.7874 0.4064)
			(end 0.7874 -0.4064)
			(stroke
				(width 0.1524)
				(type default)
			)
			(layer "B.SilkS")
		)
		(fp_line
			(start -0.7874 -0.4064)
			(end -0.7874 0.4064)
			(stroke
				(width 0.1524)
				(type default)
			)
			(layer "B.SilkS")
		)
		(fp_line
			(start 0.7874 -0.4064)
			(end -0.7874 -0.4064)
			(stroke
				(width 0.1524)
				(type default)
			)
			(layer "B.SilkS")
		)
		(fp_line
			(start -0.67945 0.3048)
			(end -0.120396 0.3048)
			(stroke
				(width 0.1)
				(type default)
			)
			(layer "B.Fab")
		)
		(fp_line
			(start -0.120396 0.3048)
			(end -0.120396 0.2794)
			(stroke
				(width 0.1)
				(type default)
			)
			(layer "B.Fab")
		)
		(fp_line
			(start 0.12065 0.3048)
			(end 0.67945 0.3048)
			(stroke
				(width 0.1)
				(type default)
			)
			(layer "B.Fab")
		)
		(fp_line
			(start 0.67945 0.3048)
			(end 0.67945 -0.305054)
			(stroke
				(width 0.1)
				(type default)
			)
			(layer "B.Fab")
		)
		(fp_line
			(start -0.120396 0.2794)
			(end 0.12065 0.2794)
			(stroke
				(width 0.1)
				(type default)
			)
			(layer "B.Fab")
		)
		(fp_line
			(start 0.12065 0.2794)
			(end 0.12065 0.3048)
			(stroke
				(width 0.1)
				(type default)
			)
			(layer "B.Fab")
		)
		(fp_line
			(start -0.12065 -0.2794)
			(end -0.12065 -0.3048)
			(stroke
				(width 0.1)
				(type default)
			)
			(layer "B.Fab")
		)
		(fp_line
			(start 0.12065 -0.2794)
			(end -0.12065 -0.2794)
			(stroke
				(width 0.1)
				(type default)
			)
			(layer "B.Fab")
		)
		(fp_line
			(start -0.67945 -0.3048)
			(end -0.67945 0.3048)
			(stroke
				(width 0.1)
				(type default)
			)
			(layer "B.Fab")
		)
		(fp_line
			(start -0.12065 -0.3048)
			(end -0.67945 -0.3048)
			(stroke
				(width 0.1)
				(type default)
			)
			(layer "B.Fab")
		)
		(fp_line
			(start 0.12065 -0.305054)
			(end 0.12065 -0.2794)
			(stroke
				(width 0.1)
				(type default)
			)
			(layer "B.Fab")
		)
		(fp_line
			(start 0.67945 -0.305054)
			(end 0.12065 -0.305054)
			(stroke
				(width 0.1)
				(type default)
			)
			(layer "B.Fab")
		)
		(pad "1" smd circle
			(at 0.40005 0 90)
			(size 0 0)
			(layers "B.Cu" "B.Mask" "B.Paste")
			(net "SMB_NIC4_LS_R_SCL")
		)
		(pad "2" smd circle
			(at -0.40005 0 90)
			(size 0 0)
			(layers "B.Cu" "B.Mask" "B.Paste")
			(net "SMB_NIC4_R_SCL")
		)
	)
	(footprint ""
		(layer "B.Cu")
		(at 186.200034 -289.724846 180)
		(property "Reference" "C3177"
			(at 0 0 0)
			(layer "B.SilkS")
			(hide yes)
			(effects
				(font
					(size 1.27 1.27)
				)
				(justify mirror)
			)
		)
		(property "Value" ""
			(at 0 0 0)
			(layer "B.Fab")
			(effects
				(font
					(size 1.27 1.27)
				)
				(justify mirror)
			)
		)
		(duplicate_pad_numbers_are_jumpers no)
		(fp_line
			(start 0.299974 0.150114)
			(end 0.299974 -0.150114)
			(stroke
				(width 0.1)
				(type default)
			)
			(layer "B.Fab")
		)
		(fp_line
			(start 0.299974 -0.150114)
			(end -0.299974 -0.150114)
			(stroke
				(width 0.1)
				(type default)
			)
			(layer "B.Fab")
		)
		(fp_line
			(start -0.299974 0.150114)
			(end 0.299974 0.150114)
			(stroke
				(width 0.1)
				(type default)
			)
			(layer "B.Fab")
		)
		(fp_line
			(start -0.299974 -0.150114)
			(end -0.299974 0.150114)
			(stroke
				(width 0.1)
				(type default)
			)
			(layer "B.Fab")
		)
		(pad "1" smd rect
			(at 0.2667 0)
			(size 0.3048 0.381)
			(layers "B.Cu" "B.Mask" "B.Paste")
			(net "P1V8_PEX")
		)
		(pad "2" smd rect
			(at -0.2667 0)
			(size 0.3048 0.381)
			(layers "B.Cu" "B.Mask" "B.Paste")
			(net "GND")
		)
	)
	(footprint ""
		(layer "B.Cu")
		(at 165.299898 -300.174914)
		(property "Reference" "C1371"
			(at 0 0 0)
			(layer "B.SilkS")
			(hide yes)
			(effects
				(font
					(size 1.27 1.27)
				)
				(justify mirror)
			)
		)
		(property "Value" ""
			(at 0 0 0)
			(layer "B.Fab")
			(effects
				(font
					(size 1.27 1.27)
				)
				(justify mirror)
			)
		)
		(duplicate_pad_numbers_are_jumpers no)
		(fp_line
			(start -0.299974 -0.150114)
			(end -0.299974 0.150114)
			(stroke
				(width 0.1)
				(type default)
			)
			(layer "B.Fab")
		)
		(fp_line
			(start -0.299974 0.150114)
			(end 0.299974 0.150114)
			(stroke
				(width 0.1)
				(type default)
			)
			(layer "B.Fab")
		)
		(fp_line
			(start 0.299974 -0.150114)
			(end -0.299974 -0.150114)
			(stroke
				(width 0.1)
				(type default)
			)
			(layer "B.Fab")
		)
		(fp_line
			(start 0.299974 0.150114)
			(end 0.299974 -0.150114)
			(stroke
				(width 0.1)
				(type default)
			)
			(layer "B.Fab")
		)
		(pad "1" smd rect
			(at 0.2667 0 180)
			(size 0.3048 0.381)
			(layers "B.Cu" "B.Mask" "B.Paste")
			(net "P0V8_PEX1")
		)
		(pad "2" smd rect
			(at -0.2667 0 180)
			(size 0.3048 0.381)
			(layers "B.Cu" "B.Mask" "B.Paste")
			(net "GND")
		)
	)
	(footprint ""
		(layer "B.Cu")
		(at 15.736062 -389.078216 180)
		(property "Reference" "C4470"
			(at 0 0 0)
			(layer "B.SilkS")
			(hide yes)
			(effects
				(font
					(size 1.27 1.27)
				)
				(justify mirror)
			)
		)
		(property "Value" ""
			(at 0 0 0)
			(layer "B.Fab")
			(effects
				(font
					(size 1.27 1.27)
				)
				(justify mirror)
			)
		)
		(duplicate_pad_numbers_are_jumpers no)
		(fp_line
			(start 0.7874 0.4064)
			(end 0.7874 -0.4064)
			(stroke
				(width 0.1524)
				(type default)
			)
			(layer "B.SilkS")
		)
		(fp_line
			(start 0.7874 -0.4064)
			(end -0.7874 -0.4064)
			(stroke
				(width 0.1524)
				(type default)
			)
			(layer "B.SilkS")
		)
		(fp_line
			(start -0.7874 0.4064)
			(end 0.7874 0.4064)
			(stroke
				(width 0.1524)
				(type default)
			)
			(layer "B.SilkS")
		)
		(fp_line
			(start -0.7874 -0.4064)
			(end -0.7874 0.4064)
			(stroke
				(width 0.1524)
				(type default)
			)
			(layer "B.SilkS")
		)
		(fp_line
			(start 0.67945 0.3048)
			(end 0.67945 -0.305054)
			(stroke
				(width 0.1)
				(type default)
			)
			(layer "B.Fab")
		)
		(fp_line
			(start 0.67945 -0.305054)
			(end 0.12065 -0.305054)
			(stroke
				(width 0.1)
				(type default)
			)
			(layer "B.Fab")
		)
		(fp_line
			(start 0.12065 0.3048)
			(end 0.67945 0.3048)
			(stroke
				(width 0.1)
				(type default)
			)
			(layer "B.Fab")
		)
		(fp_line
			(start 0.12065 0.2794)
			(end 0.12065 0.3048)
			(stroke
				(width 0.1)
				(type default)
			)
			(layer "B.Fab")
		)
		(fp_line
			(start 0.12065 -0.2794)
			(end -0.12065 -0.2794)
			(stroke
				(width 0.1)
				(type default)
			)
			(layer "B.Fab")
		)
		(fp_line
			(start 0.12065 -0.305054)
			(end 0.12065 -0.2794)
			(stroke
				(width 0.1)
				(type default)
			)
			(layer "B.Fab")
		)
		(fp_line
			(start -0.120396 0.3048)
			(end -0.120396 0.2794)
			(stroke
				(width 0.1)
				(type default)
			)
			(layer "B.Fab")
		)
		(fp_line
			(start -0.120396 0.2794)
			(end 0.12065 0.2794)
			(stroke
				(width 0.1)
				(type default)
			)
			(layer "B.Fab")
		)
		(fp_line
			(start -0.12065 -0.2794)
			(end -0.12065 -0.3048)
			(stroke
				(width 0.1)
				(type default)
			)
			(layer "B.Fab")
		)
		(fp_line
			(start -0.12065 -0.3048)
			(end -0.67945 -0.3048)
			(stroke
				(width 0.1)
				(type default)
			)
			(layer "B.Fab")
		)
		(fp_line
			(start -0.67945 0.3048)
			(end -0.120396 0.3048)
			(stroke
				(width 0.1)
				(type default)
			)
			(layer "B.Fab")
		)
		(fp_line
			(start -0.67945 -0.3048)
			(end -0.67945 0.3048)
			(stroke
				(width 0.1)
				(type default)
			)
			(layer "B.Fab")
		)
		(pad "1" smd circle
			(at 0.40005 0)
			(size 0 0)
			(layers "B.Cu" "B.Mask" "B.Paste")
			(net "P1V2_USB_8042")
		)
		(pad "2" smd circle
			(at -0.40005 0)
			(size 0 0)
			(layers "B.Cu" "B.Mask" "B.Paste")
			(net "GND")
		)
	)
	(footprint ""
		(layer "B.Cu")
		(at 108.446062 -335.453736 180)
		(property "Reference" "C2703"
			(at 0 0 0)
			(layer "B.SilkS")
			(hide yes)
			(effects
				(font
					(size 1.27 1.27)
				)
				(justify mirror)
			)
		)
		(property "Value" ""
			(at 0 0 0)
			(layer "B.Fab")
			(effects
				(font
					(size 1.27 1.27)
				)
				(justify mirror)
			)
		)
		(duplicate_pad_numbers_are_jumpers no)
		(fp_line
			(start 0.7874 0.4064)
			(end 0.7874 -0.4064)
			(stroke
				(width 0.1524)
				(type default)
			)
			(layer "B.SilkS")
		)
		(fp_line
			(start 0.7874 -0.4064)
			(end -0.7874 -0.4064)
			(stroke
				(width 0.1524)
				(type default)
			)
			(layer "B.SilkS")
		)
		(fp_line
			(start -0.7874 0.4064)
			(end 0.7874 0.4064)
			(stroke
				(width 0.1524)
				(type default)
			)
			(layer "B.SilkS")
		)
		(fp_line
			(start -0.7874 -0.4064)
			(end -0.7874 0.4064)
			(stroke
				(width 0.1524)
				(type default)
			)
			(layer "B.SilkS")
		)
		(fp_line
			(start 0.67945 0.3048)
			(end 0.67945 -0.305054)
			(stroke
				(width 0.1)
				(type default)
			)
			(layer "B.Fab")
		)
		(fp_line
			(start 0.67945 -0.305054)
			(end 0.12065 -0.305054)
			(stroke
				(width 0.1)
				(type default)
			)
			(layer "B.Fab")
		)
		(fp_line
			(start 0.12065 0.3048)
			(end 0.67945 0.3048)
			(stroke
				(width 0.1)
				(type default)
			)
			(layer "B.Fab")
		)
		(fp_line
			(start 0.12065 0.2794)
			(end 0.12065 0.3048)
			(stroke
				(width 0.1)
				(type default)
			)
			(layer "B.Fab")
		)
		(fp_line
			(start 0.12065 -0.2794)
			(end -0.12065 -0.2794)
			(stroke
				(width 0.1)
				(type default)
			)
			(layer "B.Fab")
		)
		(fp_line
			(start 0.12065 -0.305054)
			(end 0.12065 -0.2794)
			(stroke
				(width 0.1)
				(type default)
			)
			(layer "B.Fab")
		)
		(fp_line
			(start -0.120396 0.3048)
			(end -0.120396 0.2794)
			(stroke
				(width 0.1)
				(type default)
			)
			(layer "B.Fab")
		)
		(fp_line
			(start -0.120396 0.2794)
			(end 0.12065 0.2794)
			(stroke
				(width 0.1)
				(type default)
			)
			(layer "B.Fab")
		)
		(fp_line
			(start -0.12065 -0.2794)
			(end -0.12065 -0.3048)
			(stroke
				(width 0.1)
				(type default)
			)
			(layer "B.Fab")
		)
		(fp_line
			(start -0.12065 -0.3048)
			(end -0.67945 -0.3048)
			(stroke
				(width 0.1)
				(type default)
			)
			(layer "B.Fab")
		)
		(fp_line
			(start -0.67945 0.3048)
			(end -0.120396 0.3048)
			(stroke
				(width 0.1)
				(type default)
			)
			(layer "B.Fab")
		)
		(fp_line
			(start -0.67945 -0.3048)
			(end -0.67945 0.3048)
			(stroke
				(width 0.1)
				(type default)
			)
			(layer "B.Fab")
		)
		(pad "1" smd circle
			(at 0.40005 0)
			(size 0 0)
			(layers "B.Cu" "B.Mask" "B.Paste")
			(net "P3V3_CLK_BUFFER_9ZXL0451E_VZX3P3A")
		)
		(pad "2" smd circle
			(at -0.40005 0)
			(size 0 0)
			(layers "B.Cu" "B.Mask" "B.Paste")
			(net "GND")
		)
	)
)
